(kicad_pcb
	(version 20221018)
	(generator pcbnew)
	(general
    (thickness 1.656)
  )
	(paper "A4")
	(title_block
    (title "SDI-MIPI Bridge")
    (date "2023-08-09")
    (rev "1.3.4")
    (company "Antmicro")
		(comment 9 "footprints 92-101 of 190")
	)
	(layers
    (0 "F.Cu" signal)
    (1 "In1.Cu" power)
    (2 "In2.Cu" power)
    (3 "In3.Cu" signal)
    (4 "In4.Cu" signal)
    (31 "B.Cu" signal)
    (32 "B.Adhes" user "B.Adhesive")
    (33 "F.Adhes" user "F.Adhesive")
    (34 "B.Paste" user)
    (35 "F.Paste" user)
    (36 "B.SilkS" user "B.Silkscreen")
    (37 "F.SilkS" user "F.Silkscreen")
    (38 "B.Mask" user)
    (39 "F.Mask" user)
    (40 "Dwgs.User" user "User.Drawings")
    (41 "Cmts.User" user "User.Comments")
    (42 "Eco1.User" user "User.Eco1")
    (43 "Eco2.User" user "User.Eco2")
    (44 "Edge.Cuts" user)
    (45 "Margin" user)
    (46 "B.CrtYd" user "B.Courtyard")
    (47 "F.CrtYd" user "F.Courtyard")
    (48 "B.Fab" user)
    (49 "F.Fab" user)
  )
	(footprint "sdi-mipi-bridge-footprints:R_0402_1005Metric" (layer "F.Cu")
    (at 145.5 131.75 90)
    (descr "Resistor SMD 0402")
    (tags "resistor SMD 0402")
    (property "Author" "Antmicro")
    (property "License" "Apache-2.0")
    (property "MPN" "CR0402-FX-1002GLF")
    (property "Manufacturer" "Bourns")
    (property "Sheetfile" "sdi-mipi-bridge.kicad_sch")
    (property "Sheetname" "")
    (property "Tolerance" "1%")
    (property "Val" "10k")
    (property "ki_description" "10k resistor in 0402 package with 1% tolerance")
    (attr smd)
    (fp_text reference "R100" (at -5.75 0.4 90) (layer "F.SilkS")
        (effects (font (size 0.65 0.65) (thickness 0.15)) (justify left bottom))
    )
    (fp_text value "R_10k_0402" (at 0 1.4 90) (layer "F.Fab") hide
        (effects (font (size 0.7 0.7) (thickness 0.15)) (justify left bottom))
    )
    (fp_text user "${REFERENCE}" (at -0.95 3.168 90) (layer "F.Fab") hide
        (effects (font (size 0.7 0.7) (thickness 0.15)) (justify left bottom))
    )
    (fp_text user "License: Apache-2.0" (at -0.95 5.169 90) (layer "F.Fab") hide
        (effects (font (size 0.7 0.7) (thickness 0.15)) (justify left bottom))
    )
    (fp_text user "Author: Antmicro" (at -0.95 4.169 90) (layer "F.Fab") hide
        (effects (font (size 0.7 0.7) (thickness 0.15)) (justify left bottom))
    )
    (fp_rect (start -0.93 -0.47) (end 0.93 0.47)
      (stroke (width 0.05) (type solid)) (fill none) (layer "F.CrtYd"))
    (fp_rect (start -0.5 -0.25) (end 0.5 0.25)
      (stroke (width 0.15) (type solid)) (fill none) (layer "F.Fab"))
    (pad "1" smd roundrect (at -0.485 0 90) (size 0.59 0.64) (layers "F.Cu" "F.Paste" "F.Mask") (roundrect_rratio 0.25)
      (net 3 "GNDA") (pintype "passive"))
    (pad "2" smd roundrect (at 0.485 0 90) (size 0.59 0.64) (layers "F.Cu" "F.Paste" "F.Mask") (roundrect_rratio 0.25)
      (net 18 "/DVB_ASI") (pintype "passive"))
  )
	(footprint "sdi-mipi-bridge-footprints:R_0402_1005Metric" (layer "F.Cu")
    (at 148 131.75 90)
    (descr "Resistor SMD 0402")
    (tags "resistor SMD 0402")
    (property "Author" "Antmicro")
    (property "DNP" "")
    (property "License" "Apache-2.0")
    (property "MPN" "CR0402-FX-1002GLF")
    (property "Manufacturer" "Bourns")
    (property "Sheetfile" "sdi-mipi-bridge.kicad_sch")
    (property "Sheetname" "")
    (property "Tolerance" "1%")
    (property "Val" "10k")
    (property "ki_description" "10k resistor in 0402 package with 1% tolerance")
    (attr smd)
    (fp_text reference "R104" (at -5.75 0.4 90) (layer "F.SilkS")
        (effects (font (size 0.65 0.65) (thickness 0.15)) (justify left bottom))
    )
    (fp_text value "R_10k_0402" (at 0 1.4 90) (layer "F.Fab") hide
        (effects (font (size 0.7 0.7) (thickness 0.15)) (justify left bottom))
    )
    (fp_text user "License: Apache-2.0" (at -0.95 5.169 90) (layer "F.Fab") hide
        (effects (font (size 0.7 0.7) (thickness 0.15)) (justify left bottom))
    )
    (fp_text user "${REFERENCE}" (at -0.95 3.168 90) (layer "F.Fab") hide
        (effects (font (size 0.7 0.7) (thickness 0.15)) (justify left bottom))
    )
    (fp_text user "Author: Antmicro" (at -0.95 4.169 90) (layer "F.Fab") hide
        (effects (font (size 0.7 0.7) (thickness 0.15)) (justify left bottom))
    )
    (fp_rect (start -0.93 -0.47) (end 0.93 0.47)
      (stroke (width 0.05) (type solid)) (fill none) (layer "F.CrtYd"))
    (fp_rect (start -0.5 -0.25) (end 0.5 0.25)
      (stroke (width 0.15) (type solid)) (fill none) (layer "F.Fab"))
    (pad "1" smd roundrect (at -0.485 0 90) (size 0.59 0.64) (layers "F.Cu" "F.Paste" "F.Mask") (roundrect_rratio 0.25)
      (net 3 "GNDA") (pintype "passive"))
    (pad "2" smd roundrect (at 0.485 0 90) (size 0.59 0.64) (layers "F.Cu" "F.Paste" "F.Mask") (roundrect_rratio 0.25)
      (net 23 "/TIM_861") (pintype "passive"))
  )
	(footprint "sdi-mipi-bridge-footprints:R_0402_1005Metric" (layer "F.Cu")
    (at 148 129.735 90)
    (descr "Resistor SMD 0402")
    (tags "resistor SMD 0402")
    (property "Author" "Antmicro")
    (property "DNP" "DNP")
    (property "License" "Apache-2.0")
    (property "MPN" "CR0402-FX-1002GLF")
    (property "Manufacturer" "Bourns")
    (property "Sheetfile" "sdi-mipi-bridge.kicad_sch")
    (property "Sheetname" "")
    (property "Tolerance" "1%")
    (property "Val" "10k")
    (property "ki_description" "10k resistor in 0402 package with 1% tolerance")
    (attr exclude_from_pos_files)
    (fp_text reference "R103" (at -0.88 7.7 90) (layer "F.SilkS")
        (effects (font (size 0.65 0.65) (thickness 0.15)) (justify left bottom))
    )
    (fp_text value "R_10k_0402" (at 0 1.4 90) (layer "F.Fab") hide
        (effects (font (size 0.7 0.7) (thickness 0.15)) (justify left bottom))
    )
    (fp_text user "${REFERENCE}" (at -0.95 3.168 90) (layer "F.Fab") hide
        (effects (font (size 0.7 0.7) (thickness 0.15)) (justify left bottom))
    )
    (fp_text user "Author: Antmicro" (at -0.95 4.169 90) (layer "F.Fab") hide
        (effects (font (size 0.7 0.7) (thickness 0.15)) (justify left bottom))
    )
    (fp_text user "License: Apache-2.0" (at -0.95 5.169 90) (layer "F.Fab") hide
        (effects (font (size 0.7 0.7) (thickness 0.15)) (justify left bottom))
    )
    (fp_rect (start -0.93 -0.47) (end 0.93 0.47)
      (stroke (width 0.05) (type solid)) (fill none) (layer "F.CrtYd"))
    (fp_rect (start -0.5 -0.25) (end 0.5 0.25)
      (stroke (width 0.15) (type solid)) (fill none) (layer "F.Fab"))
    (pad "1" smd roundrect (at -0.485 0 90) (size 0.59 0.64) (layers "F.Cu" "F.Paste" "F.Mask") (roundrect_rratio 0.25)
      (net 23 "/TIM_861") (pintype "passive"))
    (pad "2" smd roundrect (at 0.485 0 90) (size 0.59 0.64) (layers "F.Cu" "F.Paste" "F.Mask") (roundrect_rratio 0.25)
      (net 76 "IO_VDD") (pintype "passive"))
  )
	(footprint "sdi-mipi-bridge-footprints:R_0402_1005Metric" (layer "B.Cu")
    (at 116.75 124 90)
    (descr "Resistor SMD 0402")
    (tags "resistor SMD 0402")
    (property "Author" "Antmicro")
    (property "License" "Apache-2.0")
    (property "MPN" "CR0402-FX-22R0GLF")
    (property "Manufacturer" "Bourns")
    (property "Sheetfile" "sdi-mipi-bridge.kicad_sch")
    (property "Sheetname" "")
    (property "Tolerance" "1%")
    (property "Val" "22R")
    (property "ki_description" "22R resistor in 0402 package with 1% tolerance")
    (attr smd)
    (fp_text reference "R1" (at 1.4 0.45 90) (layer "B.SilkS")
        (effects (font (size 0.7 0.7) (thickness 0.15)) (justify right bottom mirror))
    )
    (fp_text value "R_22R_0402" (at 0 -1.4 90) (layer "B.Fab") hide
        (effects (font (size 0.7 0.7) (thickness 0.15)) (justify right bottom mirror))
    )
    (fp_text user "Author: Antmicro" (at -0.95 -4.169 90) (layer "B.Fab") hide
        (effects (font (size 0.7 0.7) (thickness 0.15)) (justify right bottom mirror))
    )
    (fp_text user "${REFERENCE}" (at -0.95 -3.168 90) (layer "B.Fab") hide
        (effects (font (size 0.7 0.7) (thickness 0.15)) (justify right bottom mirror))
    )
    (fp_text user "License: Apache-2.0" (at -0.95 -5.169 90) (layer "B.Fab") hide
        (effects (font (size 0.7 0.7) (thickness 0.15)) (justify right bottom mirror))
    )
    (fp_rect (start -0.93 0.47) (end 0.93 -0.47)
      (stroke (width 0.05) (type solid)) (fill none) (layer "B.CrtYd"))
    (fp_rect (start -0.5 0.25) (end 0.5 -0.25)
      (stroke (width 0.15) (type solid)) (fill none) (layer "B.Fab"))
    (pad "1" smd roundrect (at -0.485 0 90) (size 0.59 0.64) (layers "B.Cu" "B.Paste" "B.Mask") (roundrect_rratio 0.25)
      (net 26 "/AUDIO_MASTER_CLK") (pintype "passive"))
    (pad "2" smd roundrect (at 0.485 0 90) (size 0.59 0.64) (layers "B.Cu" "B.Paste" "B.Mask") (roundrect_rratio 0.25)
      (net 63 "Net-(U2A-AMCLK)") (pintype "passive"))
  )
	(footprint "sdi-mipi-bridge-footprints:R_0402_1005Metric" (layer "B.Cu")
    (at 118.75 124 90)
    (descr "Resistor SMD 0402")
    (tags "resistor SMD 0402")
    (property "Author" "Antmicro")
    (property "License" "Apache-2.0")
    (property "MPN" "CR0402-FX-22R0GLF")
    (property "Manufacturer" "Bourns")
    (property "Sheetfile" "sdi-mipi-bridge.kicad_sch")
    (property "Sheetname" "")
    (property "Tolerance" "1%")
    (property "Val" "22R")
    (property "ki_description" "22R resistor in 0402 package with 1% tolerance")
    (attr smd)
    (fp_text reference "R2" (at 1.4 0.45 90) (layer "B.SilkS")
        (effects (font (size 0.7 0.7) (thickness 0.15)) (justify right bottom mirror))
    )
    (fp_text value "R_22R_0402" (at 0 -1.4 90) (layer "B.Fab") hide
        (effects (font (size 0.7 0.7) (thickness 0.15)) (justify right bottom mirror))
    )
    (fp_text user "License: Apache-2.0" (at -0.95 -5.169 90) (layer "B.Fab") hide
        (effects (font (size 0.7 0.7) (thickness 0.15)) (justify right bottom mirror))
    )
    (fp_text user "Author: Antmicro" (at -0.95 -4.169 90) (layer "B.Fab") hide
        (effects (font (size 0.7 0.7) (thickness 0.15)) (justify right bottom mirror))
    )
    (fp_text user "${REFERENCE}" (at -0.95 -3.168 90) (layer "B.Fab") hide
        (effects (font (size 0.7 0.7) (thickness 0.15)) (justify right bottom mirror))
    )
    (fp_rect (start -0.93 0.47) (end 0.93 -0.47)
      (stroke (width 0.05) (type solid)) (fill none) (layer "B.CrtYd"))
    (fp_rect (start -0.5 0.25) (end 0.5 -0.25)
      (stroke (width 0.15) (type solid)) (fill none) (layer "B.Fab"))
    (pad "1" smd roundrect (at -0.485 0 90) (size 0.59 0.64) (layers "B.Cu" "B.Paste" "B.Mask") (roundrect_rratio 0.25)
      (net 28 "/AUDIO_SERIAL_BIT_CLK") (pintype "passive"))
    (pad "2" smd roundrect (at 0.485 0 90) (size 0.59 0.64) (layers "B.Cu" "B.Paste" "B.Mask") (roundrect_rratio 0.25)
      (net 64 "Net-(U2A-ACLK)") (pintype "passive"))
  )
	(footprint "sdi-mipi-bridge-footprints:R_0402_1005Metric" (layer "B.Cu")
    (at 117.75 124 90)
    (descr "Resistor SMD 0402")
    (tags "resistor SMD 0402")
    (property "Author" "Antmicro")
    (property "License" "Apache-2.0")
    (property "MPN" "CR0402-FX-22R0GLF")
    (property "Manufacturer" "Bourns")
    (property "Sheetfile" "sdi-mipi-bridge.kicad_sch")
    (property "Sheetname" "")
    (property "Tolerance" "1%")
    (property "Val" "22R")
    (property "ki_description" "22R resistor in 0402 package with 1% tolerance")
    (attr smd)
    (fp_text reference "R3" (at 1.4 0.45 90) (layer "B.SilkS")
        (effects (font (size 0.7 0.7) (thickness 0.15)) (justify right bottom mirror))
    )
    (fp_text value "R_22R_0402" (at 0 -1.4 90) (layer "B.Fab") hide
        (effects (font (size 0.7 0.7) (thickness 0.15)) (justify right bottom mirror))
    )
    (fp_text user "${REFERENCE}" (at -0.95 -3.168 90) (layer "B.Fab") hide
        (effects (font (size 0.7 0.7) (thickness 0.15)) (justify right bottom mirror))
    )
    (fp_text user "Author: Antmicro" (at -0.95 -4.169 90) (layer "B.Fab") hide
        (effects (font (size 0.7 0.7) (thickness 0.15)) (justify right bottom mirror))
    )
    (fp_text user "License: Apache-2.0" (at -0.95 -5.169 90) (layer "B.Fab") hide
        (effects (font (size 0.7 0.7) (thickness 0.15)) (justify right bottom mirror))
    )
    (fp_rect (start -0.93 0.47) (end 0.93 -0.47)
      (stroke (width 0.05) (type solid)) (fill none) (layer "B.CrtYd"))
    (fp_rect (start -0.5 0.25) (end 0.5 -0.25)
      (stroke (width 0.15) (type solid)) (fill none) (layer "B.Fab"))
    (pad "1" smd roundrect (at -0.485 0 90) (size 0.59 0.64) (layers "B.Cu" "B.Paste" "B.Mask") (roundrect_rratio 0.25)
      (net 60 "/AUDIO_WORD_CLK") (pintype "passive"))
    (pad "2" smd roundrect (at 0.485 0 90) (size 0.59 0.64) (layers "B.Cu" "B.Paste" "B.Mask") (roundrect_rratio 0.25)
      (net 66 "Net-(U2A-WCLK)") (pintype "passive"))
  )
	(footprint "sdi-mipi-bridge-footprints:C_0402_1005Metric" (layer "B.Cu")
    (at 122.5 110.9 90)
    (descr "Capacitor SMD 0402")
    (tags "capacitor SMD 0402")
    (property "Author" "Antmicro")
    (property "Dielectric" "X7R")
    (property "License" "Apache-2.0")
    (property "MPN" "GRM155R71H103KA88D")
    (property "Manufacturer" "Murata")
    (property "Sheetfile" "sdi-mipi-bridge.kicad_sch")
    (property "Sheetname" "")
    (property "Val" "10n")
    (property "Voltage" "50V")
    (property "ki_description" " ")
    (attr smd)
    (fp_text reference "C3" (at -0.9 0.3 90) (layer "B.SilkS")
        (effects (font (size 0.7 0.7) (thickness 0.15)) (justify left bottom mirror))
    )
    (fp_text value "C_10n_0402" (at 0 -1.4 90) (layer "B.Fab") hide
        (effects (font (size 0.7 0.7) (thickness 0.15)) (justify right bottom mirror))
    )
    (fp_text user "License: Apache-2.0" (at -0.932 -5.17 90) (layer "B.Fab") hide
        (effects (font (size 0.7 0.7) (thickness 0.15)) (justify right bottom mirror))
    )
    (fp_text user "${REFERENCE}" (at -0.932 -3.168 90) (layer "B.Fab") hide
        (effects (font (size 0.7 0.7) (thickness 0.15)) (justify right bottom mirror))
    )
    (fp_text user "Author: Antmicro" (at -0.932 -4.17 90) (layer "B.Fab") hide
        (effects (font (size 0.7 0.7) (thickness 0.15)) (justify right bottom mirror))
    )
    (fp_rect (start -0.94 0.47) (end 0.94 -0.47)
      (stroke (width 0.05) (type solid)) (fill none) (layer "B.CrtYd"))
    (fp_rect (start -0.499 0.249) (end 0.499 -0.249)
      (stroke (width 0.15) (type solid)) (fill none) (layer "B.Fab"))
    (pad "1" smd roundrect (at -0.484 0 90) (size 0.59 0.64) (layers "B.Cu" "B.Paste" "B.Mask") (roundrect_rratio 0.25)
      (net 1 "GNDREF") (pintype "passive"))
    (pad "2" smd roundrect (at 0.484 0 90) (size 0.59 0.64) (layers "B.Cu" "B.Paste" "B.Mask") (roundrect_rratio 0.25)
      (net 76 "IO_VDD") (pintype "passive"))
  )
	(footprint "sdi-mipi-bridge-footprints:C_0402_1005Metric" (layer "B.Cu")
    (at 121 117.4 -90)
    (descr "Capacitor SMD 0402")
    (tags "capacitor SMD 0402")
    (property "Author" "Antmicro")
    (property "Dielectric" "X7R")
    (property "License" "Apache-2.0")
    (property "MPN" "GRM155R71H103KA88D")
    (property "Manufacturer" "Murata")
    (property "Sheetfile" "sdi-mipi-bridge.kicad_sch")
    (property "Sheetname" "")
    (property "Val" "10n")
    (property "Voltage" "50V")
    (property "ki_description" " ")
    (attr smd)
    (fp_text reference "C4" (at 1 -0.4 90) (layer "B.SilkS")
        (effects (font (size 0.7 0.7) (thickness 0.15)) (justify left bottom mirror))
    )
    (fp_text value "C_10n_0402" (at 0 -1.4 90) (layer "B.Fab") hide
        (effects (font (size 0.7 0.7) (thickness 0.15)) (justify left bottom mirror))
    )
    (fp_text user "${REFERENCE}" (at -0.932 -3.168 90) (layer "B.Fab") hide
        (effects (font (size 0.7 0.7) (thickness 0.15)) (justify left bottom mirror))
    )
    (fp_text user "License: Apache-2.0" (at -0.932 -5.17 90) (layer "B.Fab") hide
        (effects (font (size 0.7 0.7) (thickness 0.15)) (justify left bottom mirror))
    )
    (fp_text user "Author: Antmicro" (at -0.932 -4.17 90) (layer "B.Fab") hide
        (effects (font (size 0.7 0.7) (thickness 0.15)) (justify left bottom mirror))
    )
    (fp_rect (start -0.94 0.47) (end 0.94 -0.47)
      (stroke (width 0.05) (type solid)) (fill none) (layer "B.CrtYd"))
    (fp_rect (start -0.499 0.249) (end 0.499 -0.249)
      (stroke (width 0.15) (type solid)) (fill none) (layer "B.Fab"))
    (pad "1" smd roundrect (at -0.484 0 270) (size 0.59 0.64) (layers "B.Cu" "B.Paste" "B.Mask") (roundrect_rratio 0.25)
      (net 1 "GNDREF") (pintype "passive"))
    (pad "2" smd roundrect (at 0.484 0 270) (size 0.59 0.64) (layers "B.Cu" "B.Paste" "B.Mask") (roundrect_rratio 0.25)
      (net 2 "+1V2") (pintype "passive"))
  )
	(footprint "sdi-mipi-bridge-footprints:C_0402_1005Metric" (layer "B.Cu")
    (at 123.5 110.9 -90)
    (descr "Capacitor SMD 0402")
    (tags "capacitor SMD 0402")
    (property "Author" "Antmicro")
    (property "Dielectric" "X7R")
    (property "License" "Apache-2.0")
    (property "MPN" "GRM155R71H103KA88D")
    (property "Manufacturer" "Murata")
    (property "Sheetfile" "sdi-mipi-bridge.kicad_sch")
    (property "Sheetname" "")
    (property "Val" "10n")
    (property "Voltage" "50V")
    (property "ki_description" " ")
    (attr smd)
    (fp_text reference "C5" (at 0.9 -0.3 90) (layer "B.SilkS")
        (effects (font (size 0.7 0.7) (thickness 0.15)) (justify left bottom mirror))
    )
    (fp_text value "C_10n_0402" (at 0 -1.4 90) (layer "B.Fab") hide
        (effects (font (size 0.7 0.7) (thickness 0.15)) (justify left bottom mirror))
    )
    (fp_text user "${REFERENCE}" (at -0.932 -3.168 90) (layer "B.Fab") hide
        (effects (font (size 0.7 0.7) (thickness 0.15)) (justify left bottom mirror))
    )
    (fp_text user "License: Apache-2.0" (at -0.932 -5.17 90) (layer "B.Fab") hide
        (effects (font (size 0.7 0.7) (thickness 0.15)) (justify left bottom mirror))
    )
    (fp_text user "Author: Antmicro" (at -0.932 -4.17 90) (layer "B.Fab") hide
        (effects (font (size 0.7 0.7) (thickness 0.15)) (justify left bottom mirror))
    )
    (fp_rect (start -0.94 0.47) (end 0.94 -0.47)
      (stroke (width 0.05) (type solid)) (fill none) (layer "B.CrtYd"))
    (fp_rect (start -0.499 0.249) (end 0.499 -0.249)
      (stroke (width 0.15) (type solid)) (fill none) (layer "B.Fab"))
    (pad "1" smd roundrect (at -0.484 0 270) (size 0.59 0.64) (layers "B.Cu" "B.Paste" "B.Mask") (roundrect_rratio 0.25)
      (net 1 "GNDREF") (pintype "passive"))
    (pad "2" smd roundrect (at 0.484 0 270) (size 0.59 0.64) (layers "B.Cu" "B.Paste" "B.Mask") (roundrect_rratio 0.25)
      (net 76 "IO_VDD") (pintype "passive"))
  )
	(footprint "sdi-mipi-bridge-footprints:C_0402_1005Metric" (layer "B.Cu")
    (at 124.5 110.9 -90)
    (descr "Capacitor SMD 0402")
    (tags "capacitor SMD 0402")
    (property "Author" "Antmicro")
    (property "Dielectric" "X7R")
    (property "License" "Apache-2.0")
    (property "MPN" "GRM155R71H103KA88D")
    (property "Manufacturer" "Murata")
    (property "Sheetfile" "sdi-mipi-bridge.kicad_sch")
    (property "Sheetname" "")
    (property "Val" "10n")
    (property "Voltage" "50V")
    (property "ki_description" " ")
    (attr smd)
    (fp_text reference "C9" (at 0.9 -0.3 90) (layer "B.SilkS")
        (effects (font (size 0.7 0.7) (thickness 0.15)) (justify left bottom mirror))
    )
    (fp_text value "C_10n_0402" (at 0 -1.4 90) (layer "B.Fab") hide
        (effects (font (size 0.7 0.7) (thickness 0.15)) (justify left bottom mirror))
    )
    (fp_text user "License: Apache-2.0" (at -0.932 -5.17 90) (layer "B.Fab") hide
        (effects (font (size 0.7 0.7) (thickness 0.15)) (justify left bottom mirror))
    )
    (fp_text user "Author: Antmicro" (at -0.932 -4.17 90) (layer "B.Fab") hide
        (effects (font (size 0.7 0.7) (thickness 0.15)) (justify left bottom mirror))
    )
    (fp_text user "${REFERENCE}" (at -0.932 -3.168 90) (layer "B.Fab") hide
        (effects (font (size 0.7 0.7) (thickness 0.15)) (justify left bottom mirror))
    )
    (fp_rect (start -0.94 0.47) (end 0.94 -0.47)
      (stroke (width 0.05) (type solid)) (fill none) (layer "B.CrtYd"))
    (fp_rect (start -0.499 0.249) (end 0.499 -0.249)
      (stroke (width 0.15) (type solid)) (fill none) (layer "B.Fab"))
    (pad "1" smd roundrect (at -0.484 0 270) (size 0.59 0.64) (layers "B.Cu" "B.Paste" "B.Mask") (roundrect_rratio 0.25)
      (net 1 "GNDREF") (pintype "passive"))
    (pad "2" smd roundrect (at 0.484 0 270) (size 0.59 0.64) (layers "B.Cu" "B.Paste" "B.Mask") (roundrect_rratio 0.25)
      (net 76 "IO_VDD") (pintype "passive"))
  )
)
